# T6G (Grand Teton) — schematic netlist excerpt (pin names and nets, part order shuffled) for the footprints in the layout excerpt that follows; sources: Cadence DE-HDL packaged netlist, KiCad conversion of 04192023_DAF0TMB3IC0_F0TG_MB_C_brd_V02_OCP.brd

J69  SCONN288_DDR506112002KQ  IO  pkg DDR288S_1-1VXC  page 93
  VIN_BULK0  = P12V_MEM_CPU0
  RFU0  = NC
  VIN_MGMT  = P3V3_AUX
  HSCL  = I3C_SPD_DDRH_CPU0_SCL
  HSDA  = I3C_SPD_DDRH_CPU0_SDA
  VSS0  = GND
  DQ0_A  = M_H_CPU0_SA_DQ<0>
  VSS1  = GND
  DQ1_A  = M_H_CPU0_SA_DQ<1>
  VSS2  = GND
  DQS0_A_T  = M_H_CPU0_SA_DQS_DP<0>
  DQS0_A_C  = M_H_CPU0_SA_DQS_DN<0>
  VSS3  = GND
  DQ4_A  = M_H_CPU0_SA_DQ<4>
  VSS4  = GND
  DQ5_A  = M_H_CPU0_SA_DQ<5>
  VSS5  = GND
  DQ8_A  = M_H_CPU0_SA_DQ<8>
  VSS6  = GND
  DQ9_A  = M_H_CPU0_SA_DQ<9>
  VSS7  = GND
  DQS1_A_T  = M_H_CPU0_SA_DQS_DP<1>
  DQS1_A_C  = M_H_CPU0_SA_DQS_DN<1>
  VSS8  = GND
  DQ12_A  = M_H_CPU0_SA_DQ<12>
  VSS9  = GND
  DQ13_A  = M_H_CPU0_SA_DQ<13>
  VSS10  = GND
  DQ16_A  = M_H_CPU0_SA_DQ<16>
  VSS11  = GND
  DQ17_A  = M_H_CPU0_SA_DQ<17>
  VSS12  = GND
  DQS2_A_T  = M_H_CPU0_SA_DQS_DP<2>
  DQS2_A_C  = M_H_CPU0_SA_DQS_DN<2>
  VSS13  = GND
  DQ20_A  = M_H_CPU0_SA_DQ<20>
  VSS14  = GND
  DQ21_A  = M_H_CPU0_SA_DQ<21>
  VSS15  = GND
  DQ24_A  = M_H_CPU0_SA_DQ<24>
  VSS16  = GND
  DQ25_A  = M_H_CPU0_SA_DQ<25>
  VSS17  = GND
  DQS3_A_T  = M_H_CPU0_SA_DQS_DP<3>
  DQS3_A_C  = M_H_CPU0_SA_DQS_DN<3>
  VSS18  = GND
  DQ28_A  = M_H_CPU0_SA_DQ<28>
  VSS19  = GND
  DQ29_A  = M_H_CPU0_SA_DQ<29>
  VSS20  = GND
  CB0_A  = M_H_CPU0_SA_CB<0>
  VSS21  = GND
  CB1_A  = M_H_CPU0_SA_CB<1>
  VSS22  = GND
  DQS4_A_T  = M_H_CPU0_SA_DQS_DP<4>
  DQS4_A_C  = M_H_CPU0_SA_DQS_DN<4>
  VSS23  = GND
  CB4_A  = M_H_CPU0_SA_CB<4>
  VSS24  = GND
  CB5_A  = M_H_CPU0_SA_CB<5>
  VSS25  = GND
  ALERT_N  = M_H_CPU0_ALERT_N
  VSS26  = GND
  CS0_A_N  = M_H_CPU0_SA_CS_N<0>
  VSS27  = GND
  CA0_A  = M_H_CPU0_SA_CA<0>
  VSS28  = GND
  CA2_A  = M_H_CPU0_SA_CA<2>
  VSS29  = GND
  CA4_A  = M_H_CPU0_SA_CA<4>
  VSS30  = GND
  CA6_A  = M_H_CPU0_SA_CA<6>
  VSS31  = GND
  PAR_A  = M_H_CPU0_SA_PAR
  VSS32  = GND
  CA0_B  = M_H_CPU0_SB_CA<0>
  VSS33  = GND
  CA2_B  = M_H_CPU0_SB_CA<2>
  VSS34  = GND
  CA4_B  = M_H_CPU0_SB_CA<4>
  VSS35  = GND
  CA6_B  = M_H_CPU0_SB_CA<6>
  VSS36  = GND
  CS0_B_N  = M_H_CPU0_SB_CS_N<0>
  VSS37  = GND
  \lbd||rsp_a_n\  = M_H_CPU0_SA_RSP<0>
  \lbs||rsp_b_n\  = M_H_CPU0_SB_RSP<0>
  VSS38  = GND
  CB4_B  = M_H_CPU0_SB_CB<4>
  VSS39  = GND
  CB5_B  = M_H_CPU0_SB_CB<5>
  VSS40  = GND
  \dqs9_b_t||tdqs9_b_t||dbi4_b_n\  = M_H_CPU0_SB_DQS_DP<9>
  \dqs9_b_c||tdqs9_b_c\  = M_H_CPU0_SB_DQS_DN<9>
  VSS41  = GND
  CB0_B  = M_H_CPU0_SB_CB<0>
  VSS42  = GND
  CB1_B  = M_H_CPU0_SB_CB<1>
  VSS43  = GND
  DQ0_B  = M_H_CPU0_SB_DQ<0>
  VSS44  = GND
  DQ1_B  = M_H_CPU0_SB_DQ<1>
  VSS45  = GND
  DQS0_B_T  = M_H_CPU0_SB_DQS_DP<0>
  DQS0_B_C  = M_H_CPU0_SB_DQS_DN<0>
  VSS46  = GND
  DQ4_B  = M_H_CPU0_SB_DQ<4>
  VSS47  = GND
  DQ5_B  = M_H_CPU0_SB_DQ<5>
  VSS48  = GND
  DQ8_B  = M_H_CPU0_SB_DQ<8>
  VSS49  = GND
  DQ9_B  = M_H_CPU0_SB_DQ<9>
  VSS50  = GND
  DQS1_B_T  = M_H_CPU0_SB_DQS_DP<1>
  DQS1_B_C  = M_H_CPU0_SB_DQS_DN<1>
  VSS51  = GND
  DQ12_B  = M_H_CPU0_SB_DQ<12>
  VSS52  = GND
  DQ13_B  = M_H_CPU0_SB_DQ<13>
  VSS53  = GND
  DQ16_B  = M_H_CPU0_SB_DQ<16>
  VSS54  = GND
  DQ17_B  = M_H_CPU0_SB_DQ<17>
  VSS55  = GND
  DQS2_B_T  = M_H_CPU0_SB_DQS_DP<2>
  DQS2_B_C  = M_H_CPU0_SB_DQS_DN<2>
  VSS56  = GND
  DQ20_B  = M_H_CPU0_SB_DQ<20>
  VSS57  = GND
  DQ21_B  = M_H_CPU0_SB_DQ<21>
  VSS58  = GND
  DQ24_B  = M_H_CPU0_SB_DQ<24>
  VSS59  = GND
  DQ25_B  = M_H_CPU0_SB_DQ<25>
  VSS60  = GND
  DQS3_B_T  = M_H_CPU0_SB_DQS_DP<3>
  DQS3_B_C  = M_H_CPU0_SB_DQS_DN<3>
  VSS61  = GND
  DQ28_B  = M_H_CPU0_SB_DQ<28>
  VSS62  = GND
  DQ29_B  = M_H_CPU0_SB_DQ<29>
  VSS63  = GND
  RFU1  = NC
  VIN_BULK1  = P12V_MEM_CPU0
  VIN_BULK2  = P12V_MEM_CPU0
  \pwr_good||fail_n\  = PWRGD_CHH_CPU0_DIMM
  HAS  = PD_CHH_CPU0_DIMM_SAA
  RFU2  = NC
  RFU3  = NC
  VSS64  = GND
  DQ2_A  = M_H_CPU0_SA_DQ<2>
  VSS65  = GND
  DQ3_A  = M_H_CPU0_SA_DQ<3>
  VSS66  = GND
  \dqs5_a_c||tdqs5_a_c||dqs5_a_t||tdqs5_a_t\  = M_H_CPU0_SA_DQS_DN<5>
  \dqs5_a_t||tdqs5_a_t\  = M_H_CPU0_SA_DQS_DP<5>
  VSS67  = GND
  DQ6_A  = M_H_CPU0_SA_DQ<6>
  VSS68  = GND
  DQ7_A  = M_H_CPU0_SA_DQ<7>
  VSS69  = GND
  DQ10_A  = M_H_CPU0_SA_DQ<10>
  VSS70  = GND
  DQ11_A  = M_H_CPU0_SA_DQ<11>
  VSS71  = GND
  \dqs6_a_c||tdqs6_a_c||dqs6_a_t||tdqs6_a_t\  = M_H_CPU0_SA_DQS_DN<6>
  \dqs6_a_t||tdqs6_a_t\  = M_H_CPU0_SA_DQS_DP<6>
  VSS72  = GND
  DQ14_A  = M_H_CPU0_SA_DQ<14>
  VSS73  = GND
  DQ15_A  = M_H_CPU0_SA_DQ<15>
  VSS74  = GND
  DQ18_A  = M_H_CPU0_SA_DQ<18>
  VSS75  = GND
  DQ19_A  = M_H_CPU0_SA_DQ<19>
  VSS76  = GND
  \dqs7_a_c||tdqs7_a_c\  = M_H_CPU0_SA_DQS_DN<7>
  \dqs7_a_t||tdqs7_a_t\  = M_H_CPU0_SA_DQS_DP<7>
  VSS77  = GND
  DQ22_A  = M_H_CPU0_SA_DQ<22>
  VSS78  = GND
  DQ23_A  = M_H_CPU0_SA_DQ<23>
  VSS79  = GND
  DQ26_A  = M_H_CPU0_SA_DQ<26>
  VSS80  = GND
  DQ27_A  = M_H_CPU0_SA_DQ<27>
  VSS81  = GND
  \dqs8_a_c||tdqs8_a_c\  = M_H_CPU0_SA_DQS_DN<8>
  \dqs8_a_t||tdqs8_a_t\  = M_H_CPU0_SA_DQS_DP<8>
  VSS82  = GND
  DQ30_A  = M_H_CPU0_SA_DQ<30>
  VSS83  = GND
  DQ31_A  = M_H_CPU0_SA_DQ<31>
  VSS84  = GND
  CB2_A  = M_H_CPU0_SA_CB<2>
  VSS85  = GND
  CB3_A  = M_H_CPU0_SA_CB<3>
  VSS86  = GND
  \dqs9_a_c||tdqs9_a_c\  = M_H_CPU0_SA_DQS_DN<9>
  \dqs9_a_t||tdqs9_a_t\  = M_H_CPU0_SA_DQS_DP<9>
  VSS87  = GND
  CB6_A  = M_H_CPU0_SA_CB<6>
  VSS88  = GND
  CB7_A  = M_H_CPU0_SA_CB<7>
  VSS89  = GND
  RESET_N  = M_H_CPU0_RESET_N
  VSS90  = GND
  CS1_A_N  = M_H_CPU0_SA_CS_N<1>
  VSS91  = GND
  CA1_A  = M_H_CPU0_SA_CA<1>
  VSS92  = GND
  CA3_A  = M_H_CPU0_SA_CA<3>
  VSS93  = GND
  CA5_A  = M_H_CPU0_SA_CA<5>
  VSS94  = GND
  CK_T  = M_H_CPU0_CLK_DP<0>
  CK_C  = M_H_CPU0_CLK_DN<0>
  VSS95  = GND
  RFU4  = NC
  CA1_B  = M_H_CPU0_SB_CA<1>
  VSS96  = GND
  CA3_B  = M_H_CPU0_SB_CA<3>
  VSS97  = GND
  CA5_B  = M_H_CPU0_SB_CA<5>
  VSS98  = GND
  PAR_B  = M_H_CPU0_SB_PAR
  VSS99  = GND
  CS1_B_N  = M_H_CPU0_SB_CS_N<1>
  VSS100  = GND
  RFU5  = NC
  RFU6  = NC
  VSS101  = GND
  CB6_B  = M_H_CPU0_SB_CB<6>
  VSS102  = GND
  CB7_B  = M_H_CPU0_SB_CB<7>
  VSS103  = GND
  DQS4_B_C  = M_H_CPU0_SB_DQS_DN<4>
  DQS4_B_T  = M_H_CPU0_SB_DQS_DP<4>
  VSS104  = GND
  CB2_B  = M_H_CPU0_SB_CB<2>
  VSS105  = GND
  CB3_B  = M_H_CPU0_SB_CB<3>
  VSS106  = GND
  DQ2_B  = M_H_CPU0_SB_DQ<2>
  VSS107  = GND
  DQ3_B  = M_H_CPU0_SB_DQ<3>
  VSS108  = GND
  \dqs5_b_c||tdqs5_b_c\  = M_H_CPU0_SB_DQS_DN<5>
  \dqs5_b_t||tdqs5_b_t\  = M_H_CPU0_SB_DQS_DP<5>
  VSS109  = GND
  DQ6_B  = M_H_CPU0_SB_DQ<6>
  VSS110  = GND
  DQ7_B  = M_H_CPU0_SB_DQ<7>
  VSS111  = GND
  DQ10_B  = M_H_CPU0_SB_DQ<10>
  VSS112  = GND
  DQ11_B  = M_H_CPU0_SB_DQ<11>
  VSS113  = GND
  \dqs6_b_c||tdqs6_b_c\  = M_H_CPU0_SB_DQS_DN<6>
  \dqs6_b_t||tdqs6_b_t\  = M_H_CPU0_SB_DQS_DP<6>
  VSS114  = GND
  DQ14_B  = M_H_CPU0_SB_DQ<14>
  VSS115  = GND
  DQ15_B  = M_H_CPU0_SB_DQ<15>
  VSS116  = GND
  DQ18_B  = M_H_CPU0_SB_DQ<18>
  VSS117  = GND
  DQ19_B  = M_H_CPU0_SB_DQ<19>
  VSS118  = GND
  \dqs7_b_c||tdqs7_b_c\  = M_H_CPU0_SB_DQS_DN<7>
  \dqs7_b_t||tdqs7_b_t\  = M_H_CPU0_SB_DQS_DP<7>
  VSS119  = GND
  DQ22_B  = M_H_CPU0_SB_DQ<22>
  VSS120  = GND
  DQ23_B  = M_H_CPU0_SB_DQ<23>
  VSS121  = GND
  DQ26_B  = M_H_CPU0_SB_DQ<26>
  VSS122  = GND
  DQ27_B  = M_H_CPU0_SB_DQ<27>
  VSS123  = GND
  \dqs8_b_c||tdqs8_b_c\  = M_H_CPU0_SB_DQS_DN<8>
  \dqs8_b_t||tdqs8_b_t\  = M_H_CPU0_SB_DQS_DP<8>
  VSS124  = GND
  DQ30_B  = M_H_CPU0_SB_DQ<30>
  VSS125  = GND
  DQ31_B  = M_H_CPU0_SB_DQ<31>
  VSS126  = GND
  G1  = GND
  G2  = GND
  G3  = GND

(kicad_pcb
	(version 20260206)
	(generator "pcbnew")
	(generator_version "10.0")
	(general
		(thickness 1.6)
		(legacy_teardrops no)
	)
	(paper "A4")
	(title_block
		(title "04192023_DAF0TMB3IC0_F0TG_MB_C_brd_V02_OCP.brd")
		(comment 1 "Grand Teton / footprint 2335 of 8354 (J69), pads 139-184 of 291")
	)
	(layers
		(0 "F.Cu" signal "TOP")
		(4 "In1.Cu" signal "GND")
		(6 "In2.Cu" signal "IN1")
		(8 "In3.Cu" signal "GND1")
		(10 "In4.Cu" signal "IN2")
		(12 "In5.Cu" signal "GND2")
		(14 "In6.Cu" signal "IN3")
		(16 "In7.Cu" signal "GND3")
		(18 "In8.Cu" signal "VCC")
		(20 "In9.Cu" signal "VCC1")
		(22 "In10.Cu" signal "GND4")
		(24 "In11.Cu" signal "IN4")
		(26 "In12.Cu" signal "GND5")
		(28 "In13.Cu" signal "IN5")
		(30 "In14.Cu" signal "GND6")
		(32 "In15.Cu" signal "IN6")
		(34 "In16.Cu" signal "GND7")
		(2 "B.Cu" signal "BOTTOM")
		(9 "F.Adhes" user "F.Adhesive")
		(11 "B.Adhes" user "B.Adhesive")
		(13 "F.Paste" user "Package Geometry/Pastemask Top")
		(15 "B.Paste" user "Package Geometry/Pastemask Bottom")
		(5 "F.SilkS" user "Ref Des/Silkscreen Top")
		(7 "B.SilkS" user "Ref Des/Silkscreen Bottom")
		(1 "F.Mask" user "Board Geometry/Soldermask Top")
		(3 "B.Mask" user "Board Geometry/Soldermask Bottom")
		(17 "Dwgs.User" user "User.Drawings")
		(19 "Cmts.User" user "User.Comments")
		(21 "Eco1.User" user "User.Eco1")
		(23 "Eco2.User" user "User.Eco2")
		(25 "Edge.Cuts" user "Board Geometry/Outline")
		(27 "Margin" user)
		(31 "F.CrtYd" user "Package Geometry/Place Bound Top")
		(29 "B.CrtYd" user "Package Geometry/Place Bound Bottom")
		(35 "F.Fab" user "Ref Des/Assembly Top")
		(33 "B.Fab" user "Ref Des/Assembly Bottom")
	)
	(footprint ""
		(layer "F.Cu")
		(at 421.962072 -255.560068 180)
		(property "Reference" "J69"
			(at 3.448304 81.947512 0)
			(unlocked yes)
			(layer "F.SilkS")
			(effects
				(font
					(size 0.7874 0.5842)
					(thickness 0.1524)
				)
			)
		)
		(property "Value" ""
			(at 0 0 180)
			(layer "F.Fab")
			(effects
				(font
					(size 1.27 1.27)
				)
			)
		)
		(duplicate_pad_numbers_are_jumpers no)
		(pad "139" smd rect
			(at -2.050034 59.075066 90)
			(size 0.519938 1.4986)
			(layers "F.Cu" "F.Mask" "F.Paste")
			(net "GND")
		)
		(pad "140" smd rect
			(at -2.050034 59.92495 90)
			(size 0.519938 1.4986)
			(layers "F.Cu" "F.Mask" "F.Paste")
			(net "M_H_CPU0_SB_DQ<28>")
		)
		(pad "141" smd rect
			(at -2.050034 60.775088 90)
			(size 0.519938 1.4986)
			(layers "F.Cu" "F.Mask" "F.Paste")
			(net "GND")
		)
		(pad "142" smd rect
			(at -2.050034 61.624972 90)
			(size 0.519938 1.4986)
			(layers "F.Cu" "F.Mask" "F.Paste")
			(net "M_H_CPU0_SB_DQ<29>")
		)
		(pad "143" smd rect
			(at -2.050034 62.47511 90)
			(size 0.519938 1.4986)
			(layers "F.Cu" "F.Mask" "F.Paste")
			(net "GND")
		)
		(pad "144" smd rect
			(at -2.050034 63.324994 90)
			(size 0.519938 1.4986)
			(layers "F.Cu" "F.Mask" "F.Paste")
			(net "Net_2348")
		)
		(pad "145" smd rect
			(at 2.050034 -63.324994 90)
			(size 0.519938 1.4986)
			(layers "F.Cu" "F.Mask" "F.Paste")
			(net "P12V_MEM_CPU0")
		)
		(pad "146" smd rect
			(at 2.050034 -62.47511 90)
			(size 0.519938 1.4986)
			(layers "F.Cu" "F.Mask" "F.Paste")
			(net "P12V_MEM_CPU0")
		)
		(pad "147" smd rect
			(at 2.050034 -61.624972 90)
			(size 0.519938 1.4986)
			(layers "F.Cu" "F.Mask" "F.Paste")
			(net "PWRGD_CHH_CPU0_DIMM")
		)
		(pad "148" smd rect
			(at 2.050034 -60.775088 90)
			(size 0.519938 1.4986)
			(layers "F.Cu" "F.Mask" "F.Paste")
			(net "PD_CHH_CPU0_DIMM_SAA")
		)
		(pad "149" smd rect
			(at 2.050034 -59.92495 90)
			(size 0.519938 1.4986)
			(layers "F.Cu" "F.Mask" "F.Paste")
			(net "Net_2349")
		)
		(pad "150" smd rect
			(at 2.050034 -59.075066 90)
			(size 0.519938 1.4986)
			(layers "F.Cu" "F.Mask" "F.Paste")
			(net "Net_2350")
		)
		(pad "151" smd rect
			(at 2.050034 -58.224928 90)
			(size 0.519938 1.4986)
			(layers "F.Cu" "F.Mask" "F.Paste")
			(net "GND")
		)
		(pad "152" smd rect
			(at 2.050034 -57.375044 90)
			(size 0.519938 1.4986)
			(layers "F.Cu" "F.Mask" "F.Paste")
			(net "M_H_CPU0_SA_DQ<2>")
		)
		(pad "153" smd rect
			(at 2.050034 -56.524906 90)
			(size 0.519938 1.4986)
			(layers "F.Cu" "F.Mask" "F.Paste")
			(net "GND")
		)
		(pad "154" smd rect
			(at 2.050034 -55.675022 90)
			(size 0.519938 1.4986)
			(layers "F.Cu" "F.Mask" "F.Paste")
			(net "M_H_CPU0_SA_DQ<3>")
		)
		(pad "155" smd rect
			(at 2.050034 -54.824884 90)
			(size 0.519938 1.4986)
			(layers "F.Cu" "F.Mask" "F.Paste")
			(net "GND")
		)
		(pad "156" smd rect
			(at 2.050034 -53.975 90)
			(size 0.519938 1.4986)
			(layers "F.Cu" "F.Mask" "F.Paste")
			(net "M_H_CPU0_SA_DQS_DN<5>")
		)
		(pad "157" smd rect
			(at 2.050034 -53.125116 90)
			(size 0.519938 1.4986)
			(layers "F.Cu" "F.Mask" "F.Paste")
			(net "M_H_CPU0_SA_DQS_DP<5>")
		)
		(pad "158" smd rect
			(at 2.050034 -52.274978 90)
			(size 0.519938 1.4986)
			(layers "F.Cu" "F.Mask" "F.Paste")
			(net "GND")
		)
		(pad "159" smd rect
			(at 2.050034 -51.425094 90)
			(size 0.519938 1.4986)
			(layers "F.Cu" "F.Mask" "F.Paste")
			(net "M_H_CPU0_SA_DQ<6>")
		)
		(pad "160" smd rect
			(at 2.050034 -50.574956 90)
			(size 0.519938 1.4986)
			(layers "F.Cu" "F.Mask" "F.Paste")
			(net "GND")
		)
		(pad "161" smd rect
			(at 2.050034 -49.725072 90)
			(size 0.519938 1.4986)
			(layers "F.Cu" "F.Mask" "F.Paste")
			(net "M_H_CPU0_SA_DQ<7>")
		)
		(pad "162" smd rect
			(at 2.050034 -48.874934 90)
			(size 0.519938 1.4986)
			(layers "F.Cu" "F.Mask" "F.Paste")
			(net "GND")
		)
		(pad "163" smd rect
			(at 2.050034 -48.02505 90)
			(size 0.519938 1.4986)
			(layers "F.Cu" "F.Mask" "F.Paste")
			(net "M_H_CPU0_SA_DQ<10>")
		)
		(pad "164" smd rect
			(at 2.050034 -47.174912 90)
			(size 0.519938 1.4986)
			(layers "F.Cu" "F.Mask" "F.Paste")
			(net "GND")
		)
		(pad "165" smd rect
			(at 2.050034 -46.325028 90)
			(size 0.519938 1.4986)
			(layers "F.Cu" "F.Mask" "F.Paste")
			(net "M_H_CPU0_SA_DQ<11>")
		)
		(pad "166" smd rect
			(at 2.050034 -45.47489 90)
			(size 0.519938 1.4986)
			(layers "F.Cu" "F.Mask" "F.Paste")
			(net "GND")
		)
		(pad "167" smd rect
			(at 2.050034 -44.625006 90)
			(size 0.519938 1.4986)
			(layers "F.Cu" "F.Mask" "F.Paste")
			(net "M_H_CPU0_SA_DQS_DN<6>")
		)
		(pad "168" smd rect
			(at 2.050034 -43.775122 90)
			(size 0.519938 1.4986)
			(layers "F.Cu" "F.Mask" "F.Paste")
			(net "M_H_CPU0_SA_DQS_DP<6>")
		)
		(pad "169" smd rect
			(at 2.050034 -42.924984 90)
			(size 0.519938 1.4986)
			(layers "F.Cu" "F.Mask" "F.Paste")
			(net "GND")
		)
		(pad "170" smd rect
			(at 2.050034 -42.0751 90)
			(size 0.519938 1.4986)
			(layers "F.Cu" "F.Mask" "F.Paste")
			(net "M_H_CPU0_SA_DQ<14>")
		)
		(pad "171" smd rect
			(at 2.050034 -41.224962 90)
			(size 0.519938 1.4986)
			(layers "F.Cu" "F.Mask" "F.Paste")
			(net "GND")
		)
		(pad "172" smd rect
			(at 2.050034 -40.375078 90)
			(size 0.519938 1.4986)
			(layers "F.Cu" "F.Mask" "F.Paste")
			(net "M_H_CPU0_SA_DQ<15>")
		)
		(pad "173" smd rect
			(at 2.050034 -39.52494 90)
			(size 0.519938 1.4986)
			(layers "F.Cu" "F.Mask" "F.Paste")
			(net "GND")
		)
		(pad "174" smd rect
			(at 2.050034 -38.675056 90)
			(size 0.519938 1.4986)
			(layers "F.Cu" "F.Mask" "F.Paste")
			(net "M_H_CPU0_SA_DQ<18>")
		)
		(pad "175" smd rect
			(at 2.050034 -37.824918 90)
			(size 0.519938 1.4986)
			(layers "F.Cu" "F.Mask" "F.Paste")
			(net "GND")
		)
		(pad "176" smd rect
			(at 2.050034 -36.975034 90)
			(size 0.519938 1.4986)
			(layers "F.Cu" "F.Mask" "F.Paste")
			(net "M_H_CPU0_SA_DQ<19>")
		)
		(pad "177" smd rect
			(at 2.050034 -36.124896 90)
			(size 0.519938 1.4986)
			(layers "F.Cu" "F.Mask" "F.Paste")
			(net "GND")
		)
		(pad "178" smd rect
			(at 2.050034 -35.275012 90)
			(size 0.519938 1.4986)
			(layers "F.Cu" "F.Mask" "F.Paste")
			(net "M_H_CPU0_SA_DQS_DN<7>")
		)
		(pad "179" smd rect
			(at 2.050034 -34.425128 90)
			(size 0.519938 1.4986)
			(layers "F.Cu" "F.Mask" "F.Paste")
			(net "M_H_CPU0_SA_DQS_DP<7>")
		)
		(pad "180" smd rect
			(at 2.050034 -33.57499 90)
			(size 0.519938 1.4986)
			(layers "F.Cu" "F.Mask" "F.Paste")
			(net "GND")
		)
		(pad "181" smd rect
			(at 2.050034 -32.725106 90)
			(size 0.519938 1.4986)
			(layers "F.Cu" "F.Mask" "F.Paste")
			(net "M_H_CPU0_SA_DQ<22>")
		)
		(pad "182" smd rect
			(at 2.050034 -31.874968 90)
			(size 0.519938 1.4986)
			(layers "F.Cu" "F.Mask" "F.Paste")
			(net "GND")
		)
		(pad "183" smd rect
			(at 2.050034 -31.025084 90)
			(size 0.519938 1.4986)
			(layers "F.Cu" "F.Mask" "F.Paste")
			(net "M_H_CPU0_SA_DQ<23>")
		)
		(pad "184" smd rect
			(at 2.050034 -30.174946 90)
			(size 0.519938 1.4986)
			(layers "F.Cu" "F.Mask" "F.Paste")
			(net "GND")
		)
	)
)
